# T6G (Grand Teton) — schematic netlist excerpt (pin names and nets, part order shuffled) for the footprints in the layout excerpt that follows; sources: Cadence DE-HDL packaged netlist, KiCad conversion of 04192023_DAF0TMB3IC0_F0TG_MB_C_brd_V02_OCP.brd

C609  Q_CAP  1UF 4V 20% X6S  pkg 0201  page 290 : A = P0V9_CPU0_RT1_2A ; B = GND
C7021  Q_CAPP  470UF 2.5V 20% SPCAP  pkg SMLF  page 323 : A = P0V9_CPU1_RT0_2A ; B = GND
PC389  Q_CAPP  220UF 4V 20% SPCAP  pkg SMLF  page 218 : A = PVDDCR_CPU1_P1 ; B = GND

(kicad_pcb
	(version 20260206)
	(generator "pcbnew")
	(generator_version "10.0")
	(general
		(thickness 1.6)
		(legacy_teardrops no)
	)
	(paper "A4")
	(title_block
		(title "04192023_DAF0TMB3IC0_F0TG_MB_C_brd_V02_OCP.brd")
		(comment 1 "Grand Teton / footprints 6879-6881 of 8354")
	)
	(layers
		(0 "F.Cu" signal "TOP")
		(4 "In1.Cu" signal "GND")
		(6 "In2.Cu" signal "IN1")
		(8 "In3.Cu" signal "GND1")
		(10 "In4.Cu" signal "IN2")
		(12 "In5.Cu" signal "GND2")
		(14 "In6.Cu" signal "IN3")
		(16 "In7.Cu" signal "GND3")
		(18 "In8.Cu" signal "VCC")
		(20 "In9.Cu" signal "VCC1")
		(22 "In10.Cu" signal "GND4")
		(24 "In11.Cu" signal "IN4")
		(26 "In12.Cu" signal "GND5")
		(28 "In13.Cu" signal "IN5")
		(30 "In14.Cu" signal "GND6")
		(32 "In15.Cu" signal "IN6")
		(34 "In16.Cu" signal "GND7")
		(2 "B.Cu" signal "BOTTOM")
		(9 "F.Adhes" user "F.Adhesive")
		(11 "B.Adhes" user "B.Adhesive")
		(13 "F.Paste" user "Package Geometry/Pastemask Top")
		(15 "B.Paste" user "Package Geometry/Pastemask Bottom")
		(5 "F.SilkS" user "Ref Des/Silkscreen Top")
		(7 "B.SilkS" user "Ref Des/Silkscreen Bottom")
		(1 "F.Mask" user "Board Geometry/Soldermask Top")
		(3 "B.Mask" user "Board Geometry/Soldermask Bottom")
		(17 "Dwgs.User" user "User.Drawings")
		(19 "Cmts.User" user "User.Comments")
		(21 "Eco1.User" user "User.Eco1")
		(23 "Eco2.User" user "User.Eco2")
		(25 "Edge.Cuts" user "Board Geometry/Outline")
		(27 "Margin" user)
		(31 "F.CrtYd" user "Package Geometry/Place Bound Top")
		(29 "B.CrtYd" user "Package Geometry/Place Bound Bottom")
		(35 "F.Fab" user "Ref Des/Assembly Top")
		(33 "B.Fab" user "Ref Des/Assembly Bottom")
	)
	(footprint ""
		(layer "B.Cu")
		(at 95.497904 -328.21753 -90)
		(property "Reference" "PC389"
			(at 7.567676 -3.601466 270)
			(unlocked yes)
			(layer "B.SilkS")
			(effects
				(font
					(size 0.7874 0.5842)
					(thickness 0.1524)
				)
				(justify left mirror)
			)
		)
		(property "Value" ""
			(at 0 0 90)
			(layer "B.Fab")
			(effects
				(font
					(size 1.27 1.27)
				)
				(justify mirror)
			)
		)
		(duplicate_pad_numbers_are_jumpers no)
		(fp_line
			(start -4.533392 2.249932)
			(end 4.533392 2.249932)
			(stroke
				(width 0.1524)
				(type default)
			)
			(layer "B.SilkS")
		)
		(fp_line
			(start 4.533392 2.249932)
			(end 4.533392 -2.249932)
			(stroke
				(width 0.1524)
				(type default)
			)
			(layer "B.SilkS")
		)
		(fp_line
			(start -4.533392 -2.249932)
			(end -4.533392 2.249932)
			(stroke
				(width 0.1524)
				(type default)
			)
			(layer "B.SilkS")
		)
		(fp_line
			(start 4.533392 -2.249932)
			(end -4.533392 -2.249932)
			(stroke
				(width 0.1524)
				(type default)
			)
			(layer "B.SilkS")
		)
		(fp_rect
			(start 5.39242 2.326132)
			(end 4.533392 -2.326132)
			(stroke
				(width 0)
				(type default)
			)
			(fill yes)
			(layer "B.SilkS")
		)
		(fp_line
			(start -3.750056 2.249932)
			(end 3.750056 2.249932)
			(stroke
				(width 0.1)
				(type default)
			)
			(layer "B.Fab")
		)
		(fp_line
			(start 3.750056 2.249932)
			(end 3.750056 -2.249932)
			(stroke
				(width 0.1)
				(type default)
			)
			(layer "B.Fab")
		)
		(fp_line
			(start -3.750056 -2.249932)
			(end -3.750056 2.249932)
			(stroke
				(width 0.1)
				(type default)
			)
			(layer "B.Fab")
		)
		(fp_line
			(start 3.750056 -2.249932)
			(end -3.750056 -2.249932)
			(stroke
				(width 0.1)
				(type default)
			)
			(layer "B.Fab")
		)
		(fp_text user "-"
			(at -4.603242 2.397252 270)
			(unlocked yes)
			(layer "B.SilkS")
			(effects
				(font
					(size 1.905 1.4224)
					(thickness 0.1524)
				)
				(justify left mirror)
			)
		)
		(fp_text user "+"
			(at 6.322314 0.786384 180)
			(unlocked yes)
			(layer "B.SilkS")
			(effects
				(font
					(size 1.905 1.4224)
					(thickness 0.1524)
				)
				(justify left mirror)
			)
		)
		(fp_text user "+"
			(at 6.322314 0.786384 180)
			(unlocked yes)
			(layer "B.Fab")
			(effects
				(font
					(size 1.905 1.4224)
					(thickness 0.1524)
				)
				(justify left mirror)
			)
		)
		(fp_text user "-"
			(at -4.8514 -0.14605 270)
			(unlocked yes)
			(layer "B.Fab")
			(effects
				(font
					(size 1.905 1.4224)
					(thickness 0.1524)
				)
				(justify left mirror)
			)
		)
		(pad "1" smd rect
			(at 3.199892 0 90)
			(size 2.413 2.8194)
			(layers "B.Cu" "B.Mask" "B.Paste")
			(net "PVDDCR_CPU1_P1")
		)
		(pad "2" smd rect
			(at -3.199892 0 90)
			(size 2.413 2.8194)
			(layers "B.Cu" "B.Mask" "B.Paste")
			(net "GND")
		)
	)
	(footprint ""
		(layer "B.Cu")
		(at 52.497228 -381.11303 180)
		(property "Reference" "C7021"
			(at -1.543304 -3.222752 0)
			(unlocked yes)
			(layer "B.SilkS")
			(effects
				(font
					(size 0.7874 0.5842)
					(thickness 0.1524)
				)
				(justify left mirror)
			)
		)
		(property "Value" ""
			(at 0 0 0)
			(layer "B.Fab")
			(effects
				(font
					(size 1.27 1.27)
				)
				(justify mirror)
			)
		)
		(duplicate_pad_numbers_are_jumpers no)
		(fp_line
			(start 4.84378 -2.150618)
			(end 4.842256 2.163064)
			(stroke
				(width 0.1524)
				(type default)
			)
			(layer "B.SilkS")
		)
		(fp_line
			(start 4.84378 -2.150618)
			(end 4.53898 -2.150618)
			(stroke
				(width 0.1524)
				(type default)
			)
			(layer "B.SilkS")
		)
		(fp_line
			(start 4.83108 2.150364)
			(end 4.447794 2.149348)
			(stroke
				(width 0.1524)
				(type default)
			)
			(layer "B.SilkS")
		)
		(fp_line
			(start 4.69138 -2.150618)
			(end 4.692396 2.161032)
			(stroke
				(width 0.1524)
				(type default)
			)
			(layer "B.SilkS")
		)
		(fp_line
			(start 4.53898 2.15011)
			(end 4.53898 -2.15011)
			(stroke
				(width 0.1524)
				(type default)
			)
			(layer "B.SilkS")
		)
		(fp_line
			(start 4.53898 -2.15011)
			(end -4.53898 -2.15011)
			(stroke
				(width 0.1524)
				(type default)
			)
			(layer "B.SilkS")
		)
		(fp_line
			(start 4.53898 -2.150618)
			(end 4.539742 2.152142)
			(stroke
				(width 0.1524)
				(type default)
			)
			(layer "B.SilkS")
		)
		(fp_line
			(start -4.53898 2.15011)
			(end 4.53898 2.15011)
			(stroke
				(width 0.1524)
				(type default)
			)
			(layer "B.SilkS")
		)
		(fp_line
			(start -4.53898 -2.15011)
			(end -4.53898 2.15011)
			(stroke
				(width 0.1524)
				(type default)
			)
			(layer "B.SilkS")
		)
		(fp_line
			(start 3.64998 2.15011)
			(end 3.64998 -2.15011)
			(stroke
				(width 0.1)
				(type default)
			)
			(layer "B.Fab")
		)
		(fp_line
			(start 3.64998 -2.15011)
			(end -3.64998 -2.15011)
			(stroke
				(width 0.1)
				(type default)
			)
			(layer "B.Fab")
		)
		(fp_line
			(start -3.64998 2.15011)
			(end 3.64998 2.15011)
			(stroke
				(width 0.1)
				(type default)
			)
			(layer "B.Fab")
		)
		(fp_line
			(start -3.64998 -2.15011)
			(end -3.64998 2.15011)
			(stroke
				(width 0.1)
				(type default)
			)
			(layer "B.Fab")
		)
		(fp_text user "+"
			(at 4.345432 -3.037078 180)
			(unlocked yes)
			(layer "B.SilkS")
			(effects
				(font
					(size 1.905 1.4224)
					(thickness 0.1524)
				)
				(justify left mirror)
			)
		)
		(fp_text user "-"
			(at -5.580634 -2.769108 180)
			(unlocked yes)
			(layer "B.SilkS")
			(effects
				(font
					(size 1.905 1.4224)
					(thickness 0.1524)
				)
				(justify left mirror)
			)
		)
		(fp_text user "+"
			(at 6.214872 -0.337058 180)
			(unlocked yes)
			(layer "B.Fab")
			(effects
				(font
					(size 1.905 1.4224)
					(thickness 0.1524)
				)
				(justify left mirror)
			)
		)
		(fp_text user "-"
			(at -4.313174 -0.094488 180)
			(unlocked yes)
			(layer "B.Fab")
			(effects
				(font
					(size 1.905 1.4224)
					(thickness 0.1524)
				)
				(justify left mirror)
			)
		)
		(pad "1" smd rect
			(at 3.199892 0)
			(size 2.413 2.8194)
			(layers "B.Cu" "B.Mask" "B.Paste")
			(net "P0V9_CPU1_RT0_2A")
		)
		(pad "2" smd rect
			(at -3.199892 0)
			(size 2.413 2.8194)
			(layers "B.Cu" "B.Mask" "B.Paste")
			(net "GND")
		)
	)
	(footprint ""
		(layer "B.Cu")
		(at 353.906074 -395.148562 90)
		(property "Reference" "C609"
			(at 0 0 90)
			(layer "B.SilkS")
			(hide yes)
			(effects
				(font
					(size 1.27 1.27)
				)
				(justify mirror)
			)
		)
		(property "Value" ""
			(at 0 0 90)
			(layer "B.Fab")
			(effects
				(font
					(size 1.27 1.27)
				)
				(justify mirror)
			)
		)
		(duplicate_pad_numbers_are_jumpers no)
		(fp_line
			(start 0.299974 -0.150114)
			(end -0.299974 -0.150114)
			(stroke
				(width 0.1)
				(type default)
			)
			(layer "B.Fab")
		)
		(fp_line
			(start -0.299974 -0.150114)
			(end -0.299974 0.150114)
			(stroke
				(width 0.1)
				(type default)
			)
			(layer "B.Fab")
		)
		(fp_line
			(start 0.299974 0.150114)
			(end 0.299974 -0.150114)
			(stroke
				(width 0.1)
				(type default)
			)
			(layer "B.Fab")
		)
		(fp_line
			(start -0.299974 0.150114)
			(end 0.299974 0.150114)
			(stroke
				(width 0.1)
				(type default)
			)
			(layer "B.Fab")
		)
		(pad "1" smd rect
			(at 0.2667 0 270)
			(size 0.3048 0.381)
			(layers "B.Cu" "B.Mask" "B.Paste")
			(net "P0V9_CPU0_RT1_2A")
		)
		(pad "2" smd rect
			(at -0.2667 0 270)
			(size 0.3048 0.381)
			(layers "B.Cu" "B.Mask" "B.Paste")
			(net "GND")
		)
	)
)
